(kicad_pcb
	(version 20260206)
	(generator "pcbnew")
	(generator_version "10.0")
	(general
		(thickness 1.6)
		(legacy_teardrops no)
	)
	(paper "A4")
	(title_block
		(title "v1-chassis-manager — T6M_CM_d_v01_1031_1645.brd")
		(comment 1 "Open CloudServer (Microsoft) / footprints 2143-2152 of 2512")
	)
	(layers
		(0 "F.Cu" signal "TOP")
		(4 "In1.Cu" signal "GND1")
		(6 "In2.Cu" signal "IN1")
		(8 "In3.Cu" signal "VCC1")
		(10 "In4.Cu" signal "VCC2")
		(12 "In5.Cu" signal "GND2")
		(14 "In6.Cu" signal "IN2")
		(16 "In7.Cu" signal "IN3")
		(18 "In8.Cu" signal "GND3")
		(2 "B.Cu" signal "BOTTOM")
		(9 "F.Adhes" user "F.Adhesive")
		(11 "B.Adhes" user "B.Adhesive")
		(13 "F.Paste" user "Package Geometry/Pastemask Top")
		(15 "B.Paste" user "Package Geometry/Pastemask Bottom")
		(5 "F.SilkS" user "Ref Des/Silkscreen Top")
		(7 "B.SilkS" user "Ref Des/Silkscreen Bottom")
		(1 "F.Mask" user "Board Geometry/Soldermask Top")
		(3 "B.Mask" user "Board Geometry/Soldermask Bottom")
		(17 "Dwgs.User" user "User.Drawings")
		(19 "Cmts.User" user "User.Comments")
		(21 "Eco1.User" user "User.Eco1")
		(23 "Eco2.User" user "User.Eco2")
		(25 "Edge.Cuts" user "Board Geometry/Outline")
		(27 "Margin" user)
		(31 "F.CrtYd" user "Package Geometry/Place Bound Top")
		(29 "B.CrtYd" user "Package Geometry/Place Bound Bottom")
		(35 "F.Fab" user "Ref Des/Assembly Top")
		(33 "B.Fab" user "Ref Des/Assembly Bottom")
	)
	(footprint ""
		(layer "B.Cu")
		(at 37.90442 -151.92629 180)
		(property "Reference" "C406"
			(at 6.961378 10.661396 0)
			(unlocked yes)
			(layer "B.SilkS")
			(effects
				(font
					(size 0.7874 0.5842)
					(thickness 0.1524)
				)
				(justify left mirror)
			)
		)
		(property "Value" ""
			(at 0 0 0)
			(layer "B.Fab")
			(effects
				(font
					(size 1.27 1.27)
				)
				(justify mirror)
			)
		)
		(duplicate_pad_numbers_are_jumpers no)
		(fp_line
			(start 0.7874 0.4064)
			(end 0.7874 -0.4064)
			(stroke
				(width 0.1524)
				(type default)
			)
			(layer "B.SilkS")
		)
		(fp_line
			(start 0.7874 -0.4064)
			(end -0.7874 -0.4064)
			(stroke
				(width 0.1524)
				(type default)
			)
			(layer "B.SilkS")
		)
		(fp_line
			(start 0 0.381)
			(end 0 -0.381)
			(stroke
				(width 0.1524)
				(type default)
			)
			(layer "B.SilkS")
		)
		(fp_line
			(start -0.7874 0.4064)
			(end 0.7874 0.4064)
			(stroke
				(width 0.1524)
				(type default)
			)
			(layer "B.SilkS")
		)
		(fp_line
			(start -0.7874 -0.4064)
			(end -0.7874 0.4064)
			(stroke
				(width 0.1524)
				(type default)
			)
			(layer "B.SilkS")
		)
		(fp_poly
			(pts
				(xy 0.5334 0.254) (xy 0.635 0.254) (xy 0.635 0.2286) (xy 0.635 -0.254) (xy 0.5334 -0.254) (xy 0.5334 -0.2794)
				(xy -0.5334 -0.2794) (xy -0.5334 -0.254) (xy -0.635 -0.254) (xy -0.635 0.254) (xy -0.5334 0.254)
				(xy -0.5334 0.2794) (xy 0.508 0.2794) (xy 0.5334 0.2794)
			)
			(stroke
				(width 0)
				(type default)
			)
			(fill no)
			(layer "B.CrtYd")
		)
		(pad "1" smd rect
			(at -0.40005 0)
			(size 0.4572 0.508)
			(layers "B.Cu" "B.Mask" "B.Paste")
			(net "P1V9_LAN1")
		)
		(pad "2" smd rect
			(at 0.40005 0)
			(size 0.4572 0.508)
			(layers "B.Cu" "B.Mask" "B.Paste")
			(net "GND")
		)
	)
	(footprint ""
		(layer "B.Cu")
		(at 51.849782 -70.512686)
		(property "Reference" "R36"
			(at -13.538962 31.434024 0)
			(unlocked yes)
			(layer "B.SilkS")
			(effects
				(font
					(size 0.7874 0.5842)
					(thickness 0.1524)
				)
				(justify left mirror)
			)
		)
		(property "Value" ""
			(at 0 0 0)
			(layer "B.Fab")
			(effects
				(font
					(size 1.27 1.27)
				)
				(justify mirror)
			)
		)
		(duplicate_pad_numbers_are_jumpers no)
		(fp_line
			(start -0.7874 -0.4064)
			(end -0.7874 0.4064)
			(stroke
				(width 0.1524)
				(type default)
			)
			(layer "B.SilkS")
		)
		(fp_line
			(start -0.7874 0.4064)
			(end 0.7874 0.4064)
			(stroke
				(width 0.1524)
				(type default)
			)
			(layer "B.SilkS")
		)
		(fp_line
			(start 0.7874 -0.4064)
			(end -0.7874 -0.4064)
			(stroke
				(width 0.1524)
				(type default)
			)
			(layer "B.SilkS")
		)
		(fp_line
			(start 0.7874 0.4064)
			(end 0.7874 -0.4064)
			(stroke
				(width 0.1524)
				(type default)
			)
			(layer "B.SilkS")
		)
		(fp_poly
			(pts
				(xy 0.508 0.2794) (xy 0.508 0.2286) (xy 0.635 0.2286) (xy 0.635 -0.254) (xy 0.5334 -0.254) (xy 0.5334 -0.2794)
				(xy -0.5334 -0.2794) (xy -0.5334 -0.254) (xy -0.635 -0.254) (xy -0.635 0.254) (xy -0.5334 0.254)
				(xy -0.5334 0.2794)
			)
			(stroke
				(width 0)
				(type default)
			)
			(fill no)
			(layer "B.CrtYd")
		)
		(pad "1" smd rect
			(at -0.40005 0 180)
			(size 0.4572 0.508)
			(layers "B.Cu" "B.Mask" "B.Paste")
			(net "P1V5_NODE1")
		)
		(pad "2" smd rect
			(at 0.40005 0 180)
			(size 0.4572 0.508)
			(layers "B.Cu" "B.Mask" "B.Paste")
			(net "A_NODE1_RP0_RCOMP")
		)
	)
	(footprint ""
		(layer "B.Cu")
		(at 129.54 -59.436 90)
		(property "Reference" "R1330"
			(at 1.27 0.10033 270)
			(unlocked yes)
			(layer "B.SilkS")
			(effects
				(font
					(size 0.7874 0.5842)
					(thickness 0.1524)
				)
				(justify left mirror)
			)
		)
		(property "Value" ""
			(at 0 0 90)
			(layer "B.Fab")
			(effects
				(font
					(size 1.27 1.27)
				)
				(justify mirror)
			)
		)
		(duplicate_pad_numbers_are_jumpers no)
		(fp_line
			(start 0.7874 -0.4064)
			(end -0.7874 -0.4064)
			(stroke
				(width 0.1524)
				(type default)
			)
			(layer "B.SilkS")
		)
		(fp_line
			(start -0.7874 -0.4064)
			(end -0.7874 0.4064)
			(stroke
				(width 0.1524)
				(type default)
			)
			(layer "B.SilkS")
		)
		(fp_line
			(start 0.7874 0.4064)
			(end 0.7874 -0.4064)
			(stroke
				(width 0.1524)
				(type default)
			)
			(layer "B.SilkS")
		)
		(fp_line
			(start -0.7874 0.4064)
			(end 0.7874 0.4064)
			(stroke
				(width 0.1524)
				(type default)
			)
			(layer "B.SilkS")
		)
		(fp_poly
			(pts
				(xy 0.508 0.2794) (xy 0.508 0.2286) (xy 0.635 0.2286) (xy 0.635 -0.254) (xy 0.5334 -0.254) (xy 0.5334 -0.2794)
				(xy -0.5334 -0.2794) (xy -0.5334 -0.254) (xy -0.635 -0.254) (xy -0.635 0.254) (xy -0.5334 0.254)
				(xy -0.5334 0.2794)
			)
			(stroke
				(width 0)
				(type default)
			)
			(fill no)
			(layer "B.CrtYd")
		)
		(pad "1" smd rect
			(at -0.40005 0 270)
			(size 0.4572 0.508)
			(layers "B.Cu" "B.Mask" "B.Paste")
			(net "UART_RI_P3_BUFFER_N")
		)
		(pad "2" smd rect
			(at 0.40005 0 270)
			(size 0.4572 0.508)
			(layers "B.Cu" "B.Mask" "B.Paste")
			(net "P3V3_NODE1")
		)
	)
	(footprint ""
		(layer "B.Cu")
		(at 36.964874 -133.45287 90)
		(property "Reference" "R261"
			(at -1.92659 -2.218436 270)
			(unlocked yes)
			(layer "B.SilkS")
			(effects
				(font
					(size 0.7874 0.5842)
					(thickness 0.1524)
				)
				(justify left mirror)
			)
		)
		(property "Value" ""
			(at 0 0 90)
			(layer "B.Fab")
			(effects
				(font
					(size 1.27 1.27)
				)
				(justify mirror)
			)
		)
		(duplicate_pad_numbers_are_jumpers no)
		(fp_line
			(start 0.7874 -0.4064)
			(end -0.7874 -0.4064)
			(stroke
				(width 0.1524)
				(type default)
			)
			(layer "B.SilkS")
		)
		(fp_line
			(start -0.7874 -0.4064)
			(end -0.7874 0.4064)
			(stroke
				(width 0.1524)
				(type default)
			)
			(layer "B.SilkS")
		)
		(fp_line
			(start 0.7874 0.4064)
			(end 0.7874 -0.4064)
			(stroke
				(width 0.1524)
				(type default)
			)
			(layer "B.SilkS")
		)
		(fp_line
			(start -0.7874 0.4064)
			(end 0.7874 0.4064)
			(stroke
				(width 0.1524)
				(type default)
			)
			(layer "B.SilkS")
		)
		(fp_poly
			(pts
				(xy 0.508 0.2794) (xy 0.508 0.2286) (xy 0.635 0.2286) (xy 0.635 -0.254) (xy 0.5334 -0.254) (xy 0.5334 -0.2794)
				(xy -0.5334 -0.2794) (xy -0.5334 -0.254) (xy -0.635 -0.254) (xy -0.635 0.254) (xy -0.5334 0.254)
				(xy -0.5334 0.2794)
			)
			(stroke
				(width 0)
				(type default)
			)
			(fill no)
			(layer "B.CrtYd")
		)
		(pad "1" smd rect
			(at -0.40005 0 270)
			(size 0.4572 0.508)
			(layers "B.Cu" "B.Mask" "B.Paste")
			(net "P1V538_BMC_NODE1")
		)
		(pad "2" smd rect
			(at 0.40005 0 270)
			(size 0.4572 0.508)
			(layers "B.Cu" "B.Mask" "B.Paste")
			(net "P0V75_BMC_VTTREF_NODE1")
		)
	)
	(footprint ""
		(layer "B.Cu")
		(at 52.81676 -181.992524 -90)
		(property "Reference" "C601"
			(at 3.618738 10.725912 270)
			(unlocked yes)
			(layer "B.SilkS")
			(effects
				(font
					(size 0.7874 0.5842)
					(thickness 0.1524)
				)
				(justify left mirror)
			)
		)
		(property "Value" ""
			(at 0 0 90)
			(layer "B.Fab")
			(effects
				(font
					(size 1.27 1.27)
				)
				(justify mirror)
			)
		)
		(duplicate_pad_numbers_are_jumpers no)
		(fp_line
			(start -0.7874 0.4064)
			(end 0.7874 0.4064)
			(stroke
				(width 0.1524)
				(type default)
			)
			(layer "B.SilkS")
		)
		(fp_line
			(start 0.7874 0.4064)
			(end 0.7874 -0.4064)
			(stroke
				(width 0.1524)
				(type default)
			)
			(layer "B.SilkS")
		)
		(fp_line
			(start 0 0.381)
			(end 0 -0.381)
			(stroke
				(width 0.1524)
				(type default)
			)
			(layer "B.SilkS")
		)
		(fp_line
			(start -0.7874 -0.4064)
			(end -0.7874 0.4064)
			(stroke
				(width 0.1524)
				(type default)
			)
			(layer "B.SilkS")
		)
		(fp_line
			(start 0.7874 -0.4064)
			(end -0.7874 -0.4064)
			(stroke
				(width 0.1524)
				(type default)
			)
			(layer "B.SilkS")
		)
		(fp_poly
			(pts
				(xy 0.5334 0.254) (xy 0.635 0.254) (xy 0.635 0.2286) (xy 0.635 -0.254) (xy 0.5334 -0.254) (xy 0.5334 -0.2794)
				(xy -0.5334 -0.2794) (xy -0.5334 -0.254) (xy -0.635 -0.254) (xy -0.635 0.254) (xy -0.5334 0.254)
				(xy -0.5334 0.2794) (xy 0.508 0.2794) (xy 0.5334 0.2794)
			)
			(stroke
				(width 0)
				(type default)
			)
			(fill no)
			(layer "B.CrtYd")
		)
		(pad "1" smd rect
			(at -0.40005 0 90)
			(size 0.4572 0.508)
			(layers "B.Cu" "B.Mask" "B.Paste")
			(net "PSU1_DC_OK_R_BUF")
		)
		(pad "2" smd rect
			(at 0.40005 0 90)
			(size 0.4572 0.508)
			(layers "B.Cu" "B.Mask" "B.Paste")
			(net "GND")
		)
	)
	(footprint ""
		(layer "B.Cu")
		(at 176.487582 -118.67896 90)
		(property "Reference" "C791"
			(at -4.32816 0.041148 270)
			(unlocked yes)
			(layer "B.SilkS")
			(effects
				(font
					(size 0.7874 0.5842)
					(thickness 0.1524)
				)
				(justify mirror)
			)
		)
		(property "Value" ""
			(at 0 0 90)
			(layer "B.Fab")
			(effects
				(font
					(size 1.27 1.27)
				)
				(justify mirror)
			)
		)
		(duplicate_pad_numbers_are_jumpers no)
		(fp_line
			(start 1.2954 -0.5842)
			(end -1.2954 -0.5842)
			(stroke
				(width 0.1524)
				(type default)
			)
			(layer "B.SilkS")
		)
		(fp_line
			(start 0 -0.5842)
			(end 0 0.5842)
			(stroke
				(width 0.1524)
				(type default)
			)
			(layer "B.SilkS")
		)
		(fp_line
			(start -1.2954 -0.5842)
			(end -1.2954 0.5842)
			(stroke
				(width 0.1524)
				(type default)
			)
			(layer "B.SilkS")
		)
		(fp_line
			(start 1.2954 0.5842)
			(end 1.2954 -0.5842)
			(stroke
				(width 0.1524)
				(type default)
			)
			(layer "B.SilkS")
		)
		(fp_line
			(start -1.2954 0.5842)
			(end 1.2954 0.5842)
			(stroke
				(width 0.1524)
				(type default)
			)
			(layer "B.SilkS")
		)
		(fp_poly
			(pts
				(xy -0.8636 -0.4572) (xy -0.8636 -0.3556) (xy -1.143 -0.3556) (xy -1.143 0.3556) (xy -0.8636 0.3556)
				(xy -0.8636 0.4572) (xy 0.8636 0.4572) (xy 0.8636 0.3556) (xy 1.143 0.3556) (xy 1.143 -0.3556) (xy 0.8636 -0.3556)
				(xy 0.8636 -0.4572)
			)
			(stroke
				(width 0)
				(type default)
			)
			(fill no)
			(layer "B.CrtYd")
		)
		(fp_line
			(start 0.884936 -0.504952)
			(end -0.884936 -0.504952)
			(stroke
				(width 0.1)
				(type default)
			)
			(layer "B.Fab")
		)
		(fp_line
			(start -0.884936 -0.504952)
			(end -0.884936 0.504952)
			(stroke
				(width 0.1)
				(type default)
			)
			(layer "B.Fab")
		)
		(fp_line
			(start 0.884936 0.504952)
			(end 0.884936 -0.504952)
			(stroke
				(width 0.1)
				(type default)
			)
			(layer "B.Fab")
		)
		(fp_line
			(start -0.884936 0.504952)
			(end 0.884936 0.504952)
			(stroke
				(width 0.1)
				(type default)
			)
			(layer "B.Fab")
		)
		(pad "1" smd rect
			(at -0.7366 0 180)
			(size 0.7112 0.8128)
			(layers "B.Cu" "B.Mask" "B.Paste")
			(net "P3V3_STB_NODE1")
		)
		(pad "2" smd rect
			(at 0.7366 0 180)
			(size 0.7112 0.8128)
			(layers "B.Cu" "B.Mask" "B.Paste")
			(net "GND")
		)
	)
	(footprint ""
		(layer "B.Cu")
		(at 110.44936 -176.569624 180)
		(property "Reference" "R712"
			(at 21.356828 -32.269176 0)
			(unlocked yes)
			(layer "B.SilkS")
			(effects
				(font
					(size 0.7874 0.5842)
					(thickness 0.1524)
				)
				(justify left mirror)
			)
		)
		(property "Value" ""
			(at 0 0 0)
			(layer "B.Fab")
			(effects
				(font
					(size 1.27 1.27)
				)
				(justify mirror)
			)
		)
		(duplicate_pad_numbers_are_jumpers no)
		(fp_line
			(start 0.7874 0.4064)
			(end 0.7874 -0.4064)
			(stroke
				(width 0.1524)
				(type default)
			)
			(layer "B.SilkS")
		)
		(fp_line
			(start 0.7874 -0.4064)
			(end -0.7874 -0.4064)
			(stroke
				(width 0.1524)
				(type default)
			)
			(layer "B.SilkS")
		)
		(fp_line
			(start -0.7874 0.4064)
			(end 0.7874 0.4064)
			(stroke
				(width 0.1524)
				(type default)
			)
			(layer "B.SilkS")
		)
		(fp_line
			(start -0.7874 -0.4064)
			(end -0.7874 0.4064)
			(stroke
				(width 0.1524)
				(type default)
			)
			(layer "B.SilkS")
		)
		(fp_poly
			(pts
				(xy 0.508 0.2794) (xy 0.508 0.2286) (xy 0.635 0.2286) (xy 0.635 -0.254) (xy 0.5334 -0.254) (xy 0.5334 -0.2794)
				(xy -0.5334 -0.2794) (xy -0.5334 -0.254) (xy -0.635 -0.254) (xy -0.635 0.254) (xy -0.5334 0.254)
				(xy -0.5334 0.2794)
			)
			(stroke
				(width 0)
				(type default)
			)
			(fill no)
			(layer "B.CrtYd")
		)
		(pad "1" smd rect
			(at -0.40005 0)
			(size 0.4572 0.508)
			(layers "B.Cu" "B.Mask" "B.Paste")
			(net "T5_NODE3_EN")
		)
		(pad "2" smd rect
			(at 0.40005 0)
			(size 0.4572 0.508)
			(layers "B.Cu" "B.Mask" "B.Paste")
			(net "P5V_NODE1")
		)
	)
	(footprint ""
		(layer "B.Cu")
		(at 159.25038 -148.804122 90)
		(property "Reference" "C461"
			(at -8.469122 -0.061722 270)
			(unlocked yes)
			(layer "B.SilkS")
			(effects
				(font
					(size 0.7874 0.5842)
					(thickness 0.1524)
				)
				(justify left mirror)
			)
		)
		(property "Value" ""
			(at 0 0 90)
			(layer "B.Fab")
			(effects
				(font
					(size 1.27 1.27)
				)
				(justify mirror)
			)
		)
		(duplicate_pad_numbers_are_jumpers no)
		(fp_line
			(start 0.7874 -0.4064)
			(end -0.7874 -0.4064)
			(stroke
				(width 0.1524)
				(type default)
			)
			(layer "B.SilkS")
		)
		(fp_line
			(start -0.7874 -0.4064)
			(end -0.7874 0.4064)
			(stroke
				(width 0.1524)
				(type default)
			)
			(layer "B.SilkS")
		)
		(fp_line
			(start 0 0.381)
			(end 0 -0.381)
			(stroke
				(width 0.1524)
				(type default)
			)
			(layer "B.SilkS")
		)
		(fp_line
			(start 0.7874 0.4064)
			(end 0.7874 -0.4064)
			(stroke
				(width 0.1524)
				(type default)
			)
			(layer "B.SilkS")
		)
		(fp_line
			(start -0.7874 0.4064)
			(end 0.7874 0.4064)
			(stroke
				(width 0.1524)
				(type default)
			)
			(layer "B.SilkS")
		)
		(fp_poly
			(pts
				(xy 0.5334 0.254) (xy 0.635 0.254) (xy 0.635 0.2286) (xy 0.635 -0.254) (xy 0.5334 -0.254) (xy 0.5334 -0.2794)
				(xy -0.5334 -0.2794) (xy -0.5334 -0.254) (xy -0.635 -0.254) (xy -0.635 0.254) (xy -0.5334 0.254)
				(xy -0.5334 0.2794) (xy 0.508 0.2794) (xy 0.5334 0.2794)
			)
			(stroke
				(width 0)
				(type default)
			)
			(fill no)
			(layer "B.CrtYd")
		)
		(pad "1" smd rect
			(at -0.40005 0 270)
			(size 0.4572 0.508)
			(layers "B.Cu" "B.Mask" "B.Paste")
			(net "P1V05_LAN2")
		)
		(pad "2" smd rect
			(at 0.40005 0 270)
			(size 0.4572 0.508)
			(layers "B.Cu" "B.Mask" "B.Paste")
			(net "GND")
		)
	)
	(footprint ""
		(layer "B.Cu")
		(at 47.551086 -137.376662 180)
		(property "Reference" "C233"
			(at -3.853434 0.612648 0)
			(unlocked yes)
			(layer "B.SilkS")
			(effects
				(font
					(size 0.7874 0.5842)
					(thickness 0.1524)
				)
				(justify left mirror)
			)
		)
		(property "Value" ""
			(at 0 0 0)
			(layer "B.Fab")
			(effects
				(font
					(size 1.27 1.27)
				)
				(justify mirror)
			)
		)
		(duplicate_pad_numbers_are_jumpers no)
		(fp_line
			(start 0.7874 0.4064)
			(end 0.7874 -0.4064)
			(stroke
				(width 0.1524)
				(type default)
			)
			(layer "B.SilkS")
		)
		(fp_line
			(start 0.7874 -0.4064)
			(end -0.7874 -0.4064)
			(stroke
				(width 0.1524)
				(type default)
			)
			(layer "B.SilkS")
		)
		(fp_line
			(start 0 0.381)
			(end 0 -0.381)
			(stroke
				(width 0.1524)
				(type default)
			)
			(layer "B.SilkS")
		)
		(fp_line
			(start -0.7874 0.4064)
			(end 0.7874 0.4064)
			(stroke
				(width 0.1524)
				(type default)
			)
			(layer "B.SilkS")
		)
		(fp_line
			(start -0.7874 -0.4064)
			(end -0.7874 0.4064)
			(stroke
				(width 0.1524)
				(type default)
			)
			(layer "B.SilkS")
		)
		(fp_poly
			(pts
				(xy 0.5334 0.254) (xy 0.635 0.254) (xy 0.635 0.2286) (xy 0.635 -0.254) (xy 0.5334 -0.254) (xy 0.5334 -0.2794)
				(xy -0.5334 -0.2794) (xy -0.5334 -0.254) (xy -0.635 -0.254) (xy -0.635 0.254) (xy -0.5334 0.254)
				(xy -0.5334 0.2794) (xy 0.508 0.2794) (xy 0.5334 0.2794)
			)
			(stroke
				(width 0)
				(type default)
			)
			(fill no)
			(layer "B.CrtYd")
		)
		(pad "1" smd rect
			(at -0.40005 0)
			(size 0.4572 0.508)
			(layers "B.Cu" "B.Mask" "B.Paste")
			(net "P1V538_BMC_NODE1")
		)
		(pad "2" smd rect
			(at 0.40005 0)
			(size 0.4572 0.508)
			(layers "B.Cu" "B.Mask" "B.Paste")
			(net "GND")
		)
	)
	(footprint ""
		(layer "B.Cu")
		(at 48.75022 -151.06269 180)
		(property "Reference" "C420"
			(at 11.81354 5.6134 0)
			(unlocked yes)
			(layer "B.SilkS")
			(effects
				(font
					(size 0.7874 0.5842)
					(thickness 0.1524)
				)
				(justify left mirror)
			)
		)
		(property "Value" ""
			(at 0 0 0)
			(layer "B.Fab")
			(effects
				(font
					(size 1.27 1.27)
				)
				(justify mirror)
			)
		)
		(duplicate_pad_numbers_are_jumpers no)
		(fp_line
			(start 0.7874 0.4064)
			(end 0.7874 -0.4064)
			(stroke
				(width 0.1524)
				(type default)
			)
			(layer "B.SilkS")
		)
		(fp_line
			(start 0.7874 -0.4064)
			(end -0.7874 -0.4064)
			(stroke
				(width 0.1524)
				(type default)
			)
			(layer "B.SilkS")
		)
		(fp_line
			(start 0 0.381)
			(end 0 -0.381)
			(stroke
				(width 0.1524)
				(type default)
			)
			(layer "B.SilkS")
		)
		(fp_line
			(start -0.7874 0.4064)
			(end 0.7874 0.4064)
			(stroke
				(width 0.1524)
				(type default)
			)
			(layer "B.SilkS")
		)
		(fp_line
			(start -0.7874 -0.4064)
			(end -0.7874 0.4064)
			(stroke
				(width 0.1524)
				(type default)
			)
			(layer "B.SilkS")
		)
		(fp_poly
			(pts
				(xy 0.5334 0.254) (xy 0.635 0.254) (xy 0.635 0.2286) (xy 0.635 -0.254) (xy 0.5334 -0.254) (xy 0.5334 -0.2794)
				(xy -0.5334 -0.2794) (xy -0.5334 -0.254) (xy -0.635 -0.254) (xy -0.635 0.254) (xy -0.5334 0.254)
				(xy -0.5334 0.2794) (xy 0.508 0.2794) (xy 0.5334 0.2794)
			)
			(stroke
				(width 0)
				(type default)
			)
			(fill no)
			(layer "B.CrtYd")
		)
		(pad "1" smd rect
			(at -0.40005 0)
			(size 0.4572 0.508)
			(layers "B.Cu" "B.Mask" "B.Paste")
			(net "P1V05_LAN1")
		)
		(pad "2" smd rect
			(at 0.40005 0)
			(size 0.4572 0.508)
			(layers "B.Cu" "B.Mask" "B.Paste")
			(net "GND")
		)
	)
)
